( ConstraintFile "p12v"
	( constraintHeader
		( objectKey
			( logical )
		)
		( version
			( 16.5 )
		)
		( revisionNumber
			( logicalViewRevNum 2 )
			( physicalViewRevNum 0 )
			( otherViewRevNum 0 )
		)
		( contents
			( dictionaryExtensions )
			( worksheetCustomizations )
			( electricalConstraints )
			( netClasses )
			( properties )
		)
		( precision
			( units mil )
			( numberOfDecimalPlaces 2 )
		)
	)
	( DictionaryExtensions
		( Attribute
			( Name "MATERIAL" )
			( Description " " )
			( Value
				( DataType ( dString ) )
				( Status  sProperty  sPackage )
			)
			( Objects
				( ValidObjects  oGate  oGateDefn  oBlock  oPart  oDesign  oSystem  oPartDefn )
				( NoInherit
					( oGate oPin )
				)
			)
			( Analysis
			)
		)
		( Attribute
			( Name "TOLERANCE" )
			( Description " " )
			( Value
				( DataType ( dString ) )
				( Status  sProperty  sPackage )
			)
			( Objects
				( ValidObjects  oGate  oGateDefn  oBlock  oPart  oDesign  oSystem  oPartDefn )
				( NoInherit
					( oGate oPin )
				)
			)
			( Analysis
			)
		)
		( Attribute
			( Name "WATTAGE" )
			( Description " " )
			( Value
				( DataType ( dString ) )
				( Status  sProperty  sPackage )
			)
			( Objects
				( ValidObjects  oGate  oGateDefn  oBlock  oPart  oDesign  oSystem  oPartDefn )
				( NoInherit
					( oGate oPin )
				)
			)
			( Analysis
			)
		)
		( Attribute
			( Name "CDS_LMAN_SYM_OUTLINE" )
			( Description " " )
			( Value
				( DataType ( dString ) )
				( Status  sProperty  sPackage )
			)
			( Objects
				( ValidObjects  oGate  oGateDefn  oBlock  oPart  oDesign  oSystem  oPartDefn )
				( NoInherit
					( oGate oPin )
				)
			)
			( Analysis
			)
		)
		( Attribute
			( Name "SEC_TYPE" )
			( Description " " )
			( Value
				( DataType ( dString ) )
				( Status  sProperty  sPackage )
			)
			( Objects
				( ValidObjects  oGate  oGateDefn  oBlock  oPart  oDesign  oSystem  oPartDefn )
				( NoInherit
					( oGate oPin )
				)
			)
			( Analysis
			)
		)
		( Attribute
			( Name "$sec" )
			( Description "" )
			( Value
				( DataType ( dString ) )
				( Status  sProperty )
			)
			( Objects
				( ValidObjects  oAll )
			)
			( Analysis
			)
		)
		( Attribute
			( Name "$location" )
			( Description "" )
			( Value
				( DataType ( dString ) )
				( Status  sProperty )
			)
			( Objects
				( ValidObjects  oAll )
			)
			( Analysis
			)
		)
		( Attribute
			( Name "WACKO" )
			( Description " " )
			( Value
				( DataType ( dString ) )
				( Status  sProperty  sPackage )
			)
			( Objects
				( ValidObjects  oGate  oGateDefn  oBlock  oPart  oDesign  oSystem  oPartDefn )
				( NoInherit
					( oGate oPin )
				)
			)
			( Analysis
			)
		)
		( Attribute
			( Name "BODY_TYPE" )
			( Description " " )
			( Value
				( DataType ( dString ) )
				( Status  sProperty  sPackage )
			)
			( Objects
				( ValidObjects  oGate  oBlock  oPart  oDesign  oSystem  oGateDefn  oPartDefn )
			)
			( Analysis
			)
		)
	)
	( designConstraints
		( ruleChanges
			( allRules )
			( design "p12v"
			)
			( signal "@mstr_symbols.p12v(sch_1):g"
				( objectFlag fObjectAlias )
				( objectStatus "g" )
			)
			( signal "@mstr_symbols.p12v(sch_1):page1_g"
				( objectFlag fObjectAlias )
				( objectStatus "page1_g" )
			)
			( signal "@mstr_symbols.p12v(sch_1):p12v"
				( alias ( signalRef "@mstr_symbols.p12v(sch_1):page1_p12v") )
				( alias ( signalRef "@mstr_symbols.p12v(sch_1):page1_g") )
				( alias ( signalRef "@mstr_symbols.p12v(sch_1):g") )
				( objectStatus "p12v" )
			)
			( signal "@mstr_symbols.p12v(sch_1):page1_p12v"
				( objectFlag fObjectAlias )
				( objectStatus "page1_p12v" )
			)
		)
	)
)
